# Stackup_F0T_Expander_BD_18L_3p09mm_EM-890K_VL411_Rev1_20221220.xls — Manufacuring violation (pcb-stackup)
| Description | Quanta layout design rule | The stackup design rule |  |
| Min. Innerlayer Line Width, 0.5 oz copper (mil) | 3 | NA | Normal |
| Min. Innerlayer Space, 0.5 oz copper (mil) | 3.5 | NA | Medium |
| Min. Innerlayer Line Width,   1 oz copper (mil) | 4 | 3.5 | High |
| Min. Innerlayer Space, 1 oz copper (mil) | 4 | 3 |  |
| Min. Innerlayer Line Width,   2oz copper (mil) | 6 | NA |  |
| Min. Innerlayer Space,  2oz copper (mil) | 6 | NA |  |
| Min. Outerlayer line width, 0.5oz copper foil (mil) | 3.5 | 3.5 |  |
| Min. Outerlayer Space, 0.5oz copper foil (mil) | 3.5 | 4.5 |  |
| Min. Inner Core/PP thickness (mil) | 3 | 4 |  |
| Max. Aspect Ratio for min. DHS | 12.24 | 12.42 |  |
